# T6G (Grand Teton) — schematic netlist excerpt (pin names and nets, part order shuffled) for the footprints in the layout excerpt that follows; sources: Cadence DE-HDL packaged netlist, KiCad conversion of 04192023_DAF0TMB3IC0_F0TG_MB_C_brd_V02_OCP.brd

PR6611  Q_RES  0 5% CHIP  pkg 0402LF  page 362 : A = NC_P0V9_RETIMER_CPU0_IMON5 ; B = GND
C851  Q_CAP_DIFFBUS  DIFF BUS_0.22UF 6.3V 20% X6S  pkg C0201  page 64 : \1\ = P5E_CPU0_P2_TX_C_DP<9> ; \2\ = P5E_CPU0_P2_TX_DP<9>
R1040  Q_RES  1K 1% EMPTY  pkg 0201LF  page 288 : A = P1V8_CPU0_RT_1D ; B = RT_CPU0_P1_VQPS

(kicad_pcb
	(version 20260206)
	(generator "pcbnew")
	(generator_version "10.0")
	(general
		(thickness 1.6)
		(legacy_teardrops no)
	)
	(paper "A4")
	(title_block
		(title "04192023_DAF0TMB3IC0_F0TG_MB_C_brd_V02_OCP.brd")
		(comment 1 "Grand Teton / footprints 2874-2876 of 8354")
	)
	(layers
		(0 "F.Cu" signal "TOP")
		(4 "In1.Cu" signal "GND")
		(6 "In2.Cu" signal "IN1")
		(8 "In3.Cu" signal "GND1")
		(10 "In4.Cu" signal "IN2")
		(12 "In5.Cu" signal "GND2")
		(14 "In6.Cu" signal "IN3")
		(16 "In7.Cu" signal "GND3")
		(18 "In8.Cu" signal "VCC")
		(20 "In9.Cu" signal "VCC1")
		(22 "In10.Cu" signal "GND4")
		(24 "In11.Cu" signal "IN4")
		(26 "In12.Cu" signal "GND5")
		(28 "In13.Cu" signal "IN5")
		(30 "In14.Cu" signal "GND6")
		(32 "In15.Cu" signal "IN6")
		(34 "In16.Cu" signal "GND7")
		(2 "B.Cu" signal "BOTTOM")
		(9 "F.Adhes" user "F.Adhesive")
		(11 "B.Adhes" user "B.Adhesive")
		(13 "F.Paste" user "Package Geometry/Pastemask Top")
		(15 "B.Paste" user "Package Geometry/Pastemask Bottom")
		(5 "F.SilkS" user "Ref Des/Silkscreen Top")
		(7 "B.SilkS" user "Ref Des/Silkscreen Bottom")
		(1 "F.Mask" user "Board Geometry/Soldermask Top")
		(3 "B.Mask" user "Board Geometry/Soldermask Bottom")
		(17 "Dwgs.User" user "User.Drawings")
		(19 "Cmts.User" user "User.Comments")
		(21 "Eco1.User" user "User.Eco1")
		(23 "Eco2.User" user "User.Eco2")
		(25 "Edge.Cuts" user "Board Geometry/Outline")
		(27 "Margin" user)
		(31 "F.CrtYd" user "Package Geometry/Place Bound Top")
		(29 "B.CrtYd" user "Package Geometry/Place Bound Bottom")
		(35 "F.Fab" user "Ref Des/Assembly Top")
		(33 "B.Fab" user "Ref Des/Assembly Bottom")
	)
	(footprint ""
		(layer "F.Cu")
		(at 413.93364 -378.95403 -90)
		(property "Reference" "C851"
			(at 0 0 270)
			(layer "F.SilkS")
			(hide yes)
			(effects
				(font
					(size 1.27 1.27)
				)
			)
		)
		(property "Value" ""
			(at 0 0 270)
			(layer "F.Fab")
			(effects
				(font
					(size 1.27 1.27)
				)
			)
		)
		(duplicate_pad_numbers_are_jumpers no)
		(fp_line
			(start -0.299974 0.150114)
			(end -0.299974 -0.150114)
			(stroke
				(width 0.1)
				(type default)
			)
			(layer "F.Fab")
		)
		(fp_line
			(start 0.299974 0.150114)
			(end -0.299974 0.150114)
			(stroke
				(width 0.1)
				(type default)
			)
			(layer "F.Fab")
		)
		(fp_line
			(start -0.299974 -0.150114)
			(end 0.299974 -0.150114)
			(stroke
				(width 0.1)
				(type default)
			)
			(layer "F.Fab")
		)
		(fp_line
			(start 0.299974 -0.150114)
			(end 0.299974 0.150114)
			(stroke
				(width 0.1)
				(type default)
			)
			(layer "F.Fab")
		)
		(pad "1" smd rect
			(at -0.2667 0 270)
			(size 0.3048 0.381)
			(layers "F.Cu" "F.Mask" "F.Paste")
			(net "P5E_CPU0_P2_TX_C_DP<9>")
		)
		(pad "2" smd rect
			(at 0.2667 0 270)
			(size 0.3048 0.381)
			(layers "F.Cu" "F.Mask" "F.Paste")
			(net "P5E_CPU0_P2_TX_DP<9>")
		)
	)
	(footprint ""
		(layer "F.Cu")
		(at 445.252602 -418.17671 -90)
		(property "Reference" "PR6611"
			(at 0 0 270)
			(layer "F.SilkS")
			(hide yes)
			(effects
				(font
					(size 1.27 1.27)
				)
			)
		)
		(property "Value" ""
			(at 0 0 270)
			(layer "F.Fab")
			(effects
				(font
					(size 1.27 1.27)
				)
			)
		)
		(duplicate_pad_numbers_are_jumpers no)
		(fp_line
			(start -0.7874 0.4064)
			(end -0.7874 -0.4064)
			(stroke
				(width 0.1524)
				(type default)
			)
			(layer "F.SilkS")
		)
		(fp_line
			(start 0.7874 0.4064)
			(end -0.7874 0.4064)
			(stroke
				(width 0.1524)
				(type default)
			)
			(layer "F.SilkS")
		)
		(fp_line
			(start -0.7874 -0.4064)
			(end 0.7874 -0.4064)
			(stroke
				(width 0.1524)
				(type default)
			)
			(layer "F.SilkS")
		)
		(fp_line
			(start 0.7874 -0.4064)
			(end 0.7874 0.4064)
			(stroke
				(width 0.1524)
				(type default)
			)
			(layer "F.SilkS")
		)
		(fp_line
			(start -0.67945 0.3048)
			(end -0.67945 -0.305054)
			(stroke
				(width 0.1)
				(type default)
			)
			(layer "F.Fab")
		)
		(fp_line
			(start -0.12065 0.3048)
			(end -0.67945 0.3048)
			(stroke
				(width 0.1)
				(type default)
			)
			(layer "F.Fab")
		)
		(fp_line
			(start 0.120396 0.3048)
			(end 0.120396 0.2794)
			(stroke
				(width 0.1)
				(type default)
			)
			(layer "F.Fab")
		)
		(fp_line
			(start 0.67945 0.3048)
			(end 0.120396 0.3048)
			(stroke
				(width 0.1)
				(type default)
			)
			(layer "F.Fab")
		)
		(fp_line
			(start -0.12065 0.2794)
			(end -0.12065 0.3048)
			(stroke
				(width 0.1)
				(type default)
			)
			(layer "F.Fab")
		)
		(fp_line
			(start 0.120396 0.2794)
			(end -0.12065 0.2794)
			(stroke
				(width 0.1)
				(type default)
			)
			(layer "F.Fab")
		)
		(fp_line
			(start -0.12065 -0.2794)
			(end 0.12065 -0.2794)
			(stroke
				(width 0.1)
				(type default)
			)
			(layer "F.Fab")
		)
		(fp_line
			(start 0.12065 -0.2794)
			(end 0.12065 -0.3048)
			(stroke
				(width 0.1)
				(type default)
			)
			(layer "F.Fab")
		)
		(fp_line
			(start 0.12065 -0.3048)
			(end 0.67945 -0.3048)
			(stroke
				(width 0.1)
				(type default)
			)
			(layer "F.Fab")
		)
		(fp_line
			(start 0.67945 -0.3048)
			(end 0.67945 0.3048)
			(stroke
				(width 0.1)
				(type default)
			)
			(layer "F.Fab")
		)
		(fp_line
			(start -0.67945 -0.305054)
			(end -0.12065 -0.305054)
			(stroke
				(width 0.1)
				(type default)
			)
			(layer "F.Fab")
		)
		(fp_line
			(start -0.12065 -0.305054)
			(end -0.12065 -0.2794)
			(stroke
				(width 0.1)
				(type default)
			)
			(layer "F.Fab")
		)
		(pad "1" smd circle
			(at -0.40005 0 270)
			(size 0 0)
			(layers "F.Cu" "F.Mask" "F.Paste")
			(net "NC_P0V9_RETIMER_CPU0_IMON5")
		)
		(pad "2" smd circle
			(at 0.40005 0 270)
			(size 0 0)
			(layers "F.Cu" "F.Mask" "F.Paste")
			(net "GND")
		)
	)
	(footprint ""
		(layer "F.Cu")
		(at 355.08057 -404.0124 -90)
		(property "Reference" "R1040"
			(at 0 0 270)
			(layer "F.SilkS")
			(hide yes)
			(effects
				(font
					(size 1.27 1.27)
				)
			)
		)
		(property "Value" ""
			(at 0 0 270)
			(layer "F.Fab")
			(effects
				(font
					(size 1.27 1.27)
				)
			)
		)
		(duplicate_pad_numbers_are_jumpers no)
		(fp_line
			(start -0.32512 0.175006)
			(end -0.32512 -0.175006)
			(stroke
				(width 0.1)
				(type default)
			)
			(layer "F.Fab")
		)
		(fp_line
			(start 0.32512 0.175006)
			(end -0.32512 0.175006)
			(stroke
				(width 0.1)
				(type default)
			)
			(layer "F.Fab")
		)
		(fp_line
			(start -0.32512 -0.175006)
			(end 0.32512 -0.175006)
			(stroke
				(width 0.1)
				(type default)
			)
			(layer "F.Fab")
		)
		(fp_line
			(start 0.32512 -0.175006)
			(end 0.32512 0.175006)
			(stroke
				(width 0.1)
				(type default)
			)
			(layer "F.Fab")
		)
		(pad "1" smd rect
			(at -0.2667 0 270)
			(size 0.3048 0.381)
			(layers "F.Cu" "F.Mask" "F.Paste")
			(net "P1V8_CPU0_RT_1D")
		)
		(pad "2" smd rect
			(at 0.2667 0 90)
			(size 0.3048 0.381)
			(layers "F.Cu" "F.Mask" "F.Paste")
			(net "RT_CPU0_P1_VQPS")
		)
	)
)
